(kicad_pcb
	(version 20260206)
	(generator "pcbnew")
	(generator_version "10.0")
	(general
		(thickness 1.6)
		(legacy_teardrops no)
	)
	(paper "A4")
	(title_block
		(title "04192023_DAF0TMB3IC0_F0TG_MB_C_brd_V02_OCP.brd")
		(comment 1 "Grand Teton / footprints 6588-6595 of 8354")
	)
	(layers
		(0 "F.Cu" signal "TOP")
		(4 "In1.Cu" signal "GND")
		(6 "In2.Cu" signal "IN1")
		(8 "In3.Cu" signal "GND1")
		(10 "In4.Cu" signal "IN2")
		(12 "In5.Cu" signal "GND2")
		(14 "In6.Cu" signal "IN3")
		(16 "In7.Cu" signal "GND3")
		(18 "In8.Cu" signal "VCC")
		(20 "In9.Cu" signal "VCC1")
		(22 "In10.Cu" signal "GND4")
		(24 "In11.Cu" signal "IN4")
		(26 "In12.Cu" signal "GND5")
		(28 "In13.Cu" signal "IN5")
		(30 "In14.Cu" signal "GND6")
		(32 "In15.Cu" signal "IN6")
		(34 "In16.Cu" signal "GND7")
		(2 "B.Cu" signal "BOTTOM")
		(9 "F.Adhes" user "F.Adhesive")
		(11 "B.Adhes" user "B.Adhesive")
		(13 "F.Paste" user "Package Geometry/Pastemask Top")
		(15 "B.Paste" user "Package Geometry/Pastemask Bottom")
		(5 "F.SilkS" user "Ref Des/Silkscreen Top")
		(7 "B.SilkS" user "Ref Des/Silkscreen Bottom")
		(1 "F.Mask" user "Board Geometry/Soldermask Top")
		(3 "B.Mask" user "Board Geometry/Soldermask Bottom")
		(17 "Dwgs.User" user "User.Drawings")
		(19 "Cmts.User" user "User.Comments")
		(21 "Eco1.User" user "User.Eco1")
		(23 "Eco2.User" user "User.Eco2")
		(25 "Edge.Cuts" user "Board Geometry/Outline")
		(27 "Margin" user)
		(31 "F.CrtYd" user "Package Geometry/Place Bound Top")
		(29 "B.CrtYd" user "Package Geometry/Place Bound Bottom")
		(35 "F.Fab" user "Ref Des/Assembly Top")
		(33 "B.Fab" user "Ref Des/Assembly Bottom")
	)
	(footprint ""
		(layer "B.Cu")
		(at 186.230514 -131.556506 90)
		(property "Reference" "R6798"
			(at 0 0 90)
			(layer "B.SilkS")
			(hide yes)
			(effects
				(font
					(size 1.27 1.27)
				)
				(justify mirror)
			)
		)
		(property "Value" ""
			(at 0 0 90)
			(layer "B.Fab")
			(effects
				(font
					(size 1.27 1.27)
				)
				(justify mirror)
			)
		)
		(duplicate_pad_numbers_are_jumpers no)
		(fp_line
			(start 0.7874 -0.4064)
			(end -0.7874 -0.4064)
			(stroke
				(width 0.1524)
				(type default)
			)
			(layer "B.SilkS")
		)
		(fp_line
			(start -0.7874 -0.4064)
			(end -0.7874 0.4064)
			(stroke
				(width 0.1524)
				(type default)
			)
			(layer "B.SilkS")
		)
		(fp_line
			(start 0.7874 0.4064)
			(end 0.7874 -0.4064)
			(stroke
				(width 0.1524)
				(type default)
			)
			(layer "B.SilkS")
		)
		(fp_line
			(start -0.7874 0.4064)
			(end 0.7874 0.4064)
			(stroke
				(width 0.1524)
				(type default)
			)
			(layer "B.SilkS")
		)
		(fp_line
			(start 0.67945 -0.305054)
			(end 0.12065 -0.305054)
			(stroke
				(width 0.1)
				(type default)
			)
			(layer "B.Fab")
		)
		(fp_line
			(start 0.12065 -0.305054)
			(end 0.12065 -0.2794)
			(stroke
				(width 0.1)
				(type default)
			)
			(layer "B.Fab")
		)
		(fp_line
			(start -0.12065 -0.3048)
			(end -0.67945 -0.3048)
			(stroke
				(width 0.1)
				(type default)
			)
			(layer "B.Fab")
		)
		(fp_line
			(start -0.67945 -0.3048)
			(end -0.67945 0.3048)
			(stroke
				(width 0.1)
				(type default)
			)
			(layer "B.Fab")
		)
		(fp_line
			(start 0.12065 -0.2794)
			(end -0.12065 -0.2794)
			(stroke
				(width 0.1)
				(type default)
			)
			(layer "B.Fab")
		)
		(fp_line
			(start -0.12065 -0.2794)
			(end -0.12065 -0.3048)
			(stroke
				(width 0.1)
				(type default)
			)
			(layer "B.Fab")
		)
		(fp_line
			(start 0.12065 0.2794)
			(end 0.12065 0.3048)
			(stroke
				(width 0.1)
				(type default)
			)
			(layer "B.Fab")
		)
		(fp_line
			(start -0.120396 0.2794)
			(end 0.12065 0.2794)
			(stroke
				(width 0.1)
				(type default)
			)
			(layer "B.Fab")
		)
		(fp_line
			(start 0.67945 0.3048)
			(end 0.67945 -0.305054)
			(stroke
				(width 0.1)
				(type default)
			)
			(layer "B.Fab")
		)
		(fp_line
			(start 0.12065 0.3048)
			(end 0.67945 0.3048)
			(stroke
				(width 0.1)
				(type default)
			)
			(layer "B.Fab")
		)
		(fp_line
			(start -0.120396 0.3048)
			(end -0.120396 0.2794)
			(stroke
				(width 0.1)
				(type default)
			)
			(layer "B.Fab")
		)
		(fp_line
			(start -0.67945 0.3048)
			(end -0.120396 0.3048)
			(stroke
				(width 0.1)
				(type default)
			)
			(layer "B.Fab")
		)
		(pad "1" smd circle
			(at 0.40005 0 270)
			(size 0 0)
			(layers "B.Cu" "B.Mask" "B.Paste")
			(net "RST_RT_CPU1_P3_PERST_R_N")
		)
		(pad "2" smd circle
			(at -0.40005 0 270)
			(size 0 0)
			(layers "B.Cu" "B.Mask" "B.Paste")
			(net "RST_RT_CPU1_P3_PERST_R2_N")
		)
	)
	(footprint ""
		(layer "B.Cu")
		(at 245.745 -329.184 -90)
		(property "Reference" "C1075"
			(at 0 0 90)
			(layer "B.SilkS")
			(hide yes)
			(effects
				(font
					(size 1.27 1.27)
				)
				(justify mirror)
			)
		)
		(property "Value" ""
			(at 0 0 90)
			(layer "B.Fab")
			(effects
				(font
					(size 1.27 1.27)
				)
				(justify mirror)
			)
		)
		(duplicate_pad_numbers_are_jumpers no)
		(fp_line
			(start -0.7874 0.4064)
			(end 0.7874 0.4064)
			(stroke
				(width 0.1524)
				(type default)
			)
			(layer "B.SilkS")
		)
		(fp_line
			(start 0.7874 0.4064)
			(end 0.7874 -0.4064)
			(stroke
				(width 0.1524)
				(type default)
			)
			(layer "B.SilkS")
		)
		(fp_line
			(start -0.7874 -0.4064)
			(end -0.7874 0.4064)
			(stroke
				(width 0.1524)
				(type default)
			)
			(layer "B.SilkS")
		)
		(fp_line
			(start 0.7874 -0.4064)
			(end -0.7874 -0.4064)
			(stroke
				(width 0.1524)
				(type default)
			)
			(layer "B.SilkS")
		)
		(fp_line
			(start -0.67945 0.3048)
			(end -0.120396 0.3048)
			(stroke
				(width 0.1)
				(type default)
			)
			(layer "B.Fab")
		)
		(fp_line
			(start -0.120396 0.3048)
			(end -0.120396 0.2794)
			(stroke
				(width 0.1)
				(type default)
			)
			(layer "B.Fab")
		)
		(fp_line
			(start 0.12065 0.3048)
			(end 0.67945 0.3048)
			(stroke
				(width 0.1)
				(type default)
			)
			(layer "B.Fab")
		)
		(fp_line
			(start 0.67945 0.3048)
			(end 0.67945 -0.305054)
			(stroke
				(width 0.1)
				(type default)
			)
			(layer "B.Fab")
		)
		(fp_line
			(start -0.120396 0.2794)
			(end 0.12065 0.2794)
			(stroke
				(width 0.1)
				(type default)
			)
			(layer "B.Fab")
		)
		(fp_line
			(start 0.12065 0.2794)
			(end 0.12065 0.3048)
			(stroke
				(width 0.1)
				(type default)
			)
			(layer "B.Fab")
		)
		(fp_line
			(start -0.12065 -0.2794)
			(end -0.12065 -0.3048)
			(stroke
				(width 0.1)
				(type default)
			)
			(layer "B.Fab")
		)
		(fp_line
			(start 0.12065 -0.2794)
			(end -0.12065 -0.2794)
			(stroke
				(width 0.1)
				(type default)
			)
			(layer "B.Fab")
		)
		(fp_line
			(start -0.67945 -0.3048)
			(end -0.67945 0.3048)
			(stroke
				(width 0.1)
				(type default)
			)
			(layer "B.Fab")
		)
		(fp_line
			(start -0.12065 -0.3048)
			(end -0.67945 -0.3048)
			(stroke
				(width 0.1)
				(type default)
			)
			(layer "B.Fab")
		)
		(fp_line
			(start 0.12065 -0.305054)
			(end 0.12065 -0.2794)
			(stroke
				(width 0.1)
				(type default)
			)
			(layer "B.Fab")
		)
		(fp_line
			(start 0.67945 -0.305054)
			(end 0.12065 -0.305054)
			(stroke
				(width 0.1)
				(type default)
			)
			(layer "B.Fab")
		)
		(pad "1" smd circle
			(at 0.40005 0 90)
			(size 0 0)
			(layers "B.Cu" "B.Mask" "B.Paste")
			(net "P3V3_MAX11617_2_VDD")
		)
		(pad "2" smd circle
			(at -0.40005 0 90)
			(size 0 0)
			(layers "B.Cu" "B.Mask" "B.Paste")
			(net "GND")
		)
	)
	(footprint ""
		(layer "B.Cu")
		(at 100.370386 -268.418564)
		(property "Reference" "C2378"
			(at 0 0 0)
			(layer "B.SilkS")
			(hide yes)
			(effects
				(font
					(size 1.27 1.27)
				)
				(justify mirror)
			)
		)
		(property "Value" ""
			(at 0 0 0)
			(layer "B.Fab")
			(effects
				(font
					(size 1.27 1.27)
				)
				(justify mirror)
			)
		)
		(duplicate_pad_numbers_are_jumpers no)
		(fp_line
			(start -0.7874 -0.4064)
			(end -0.7874 0.4064)
			(stroke
				(width 0.1524)
				(type default)
			)
			(layer "B.SilkS")
		)
		(fp_line
			(start -0.7874 0.4064)
			(end 0.7874 0.4064)
			(stroke
				(width 0.1524)
				(type default)
			)
			(layer "B.SilkS")
		)
		(fp_line
			(start 0.7874 -0.4064)
			(end -0.7874 -0.4064)
			(stroke
				(width 0.1524)
				(type default)
			)
			(layer "B.SilkS")
		)
		(fp_line
			(start 0.7874 0.4064)
			(end 0.7874 -0.4064)
			(stroke
				(width 0.1524)
				(type default)
			)
			(layer "B.SilkS")
		)
		(fp_line
			(start -0.67945 -0.3048)
			(end -0.67945 0.3048)
			(stroke
				(width 0.1)
				(type default)
			)
			(layer "B.Fab")
		)
		(fp_line
			(start -0.67945 0.3048)
			(end -0.120396 0.3048)
			(stroke
				(width 0.1)
				(type default)
			)
			(layer "B.Fab")
		)
		(fp_line
			(start -0.12065 -0.3048)
			(end -0.67945 -0.3048)
			(stroke
				(width 0.1)
				(type default)
			)
			(layer "B.Fab")
		)
		(fp_line
			(start -0.12065 -0.2794)
			(end -0.12065 -0.3048)
			(stroke
				(width 0.1)
				(type default)
			)
			(layer "B.Fab")
		)
		(fp_line
			(start -0.120396 0.2794)
			(end 0.12065 0.2794)
			(stroke
				(width 0.1)
				(type default)
			)
			(layer "B.Fab")
		)
		(fp_line
			(start -0.120396 0.3048)
			(end -0.120396 0.2794)
			(stroke
				(width 0.1)
				(type default)
			)
			(layer "B.Fab")
		)
		(fp_line
			(start 0.12065 -0.305054)
			(end 0.12065 -0.2794)
			(stroke
				(width 0.1)
				(type default)
			)
			(layer "B.Fab")
		)
		(fp_line
			(start 0.12065 -0.2794)
			(end -0.12065 -0.2794)
			(stroke
				(width 0.1)
				(type default)
			)
			(layer "B.Fab")
		)
		(fp_line
			(start 0.12065 0.2794)
			(end 0.12065 0.3048)
			(stroke
				(width 0.1)
				(type default)
			)
			(layer "B.Fab")
		)
		(fp_line
			(start 0.12065 0.3048)
			(end 0.67945 0.3048)
			(stroke
				(width 0.1)
				(type default)
			)
			(layer "B.Fab")
		)
		(fp_line
			(start 0.67945 -0.305054)
			(end 0.12065 -0.305054)
			(stroke
				(width 0.1)
				(type default)
			)
			(layer "B.Fab")
		)
		(fp_line
			(start 0.67945 0.3048)
			(end 0.67945 -0.305054)
			(stroke
				(width 0.1)
				(type default)
			)
			(layer "B.Fab")
		)
		(pad "1" smd circle
			(at 0.40005 0 180)
			(size 0 0)
			(layers "B.Cu" "B.Mask" "B.Paste")
			(net "PVDDCR_CPU1_P1")
		)
		(pad "2" smd circle
			(at -0.40005 0 180)
			(size 0 0)
			(layers "B.Cu" "B.Mask" "B.Paste")
			(net "GND")
		)
	)
	(footprint ""
		(layer "B.Cu")
		(at 56.97855 -386.766562 90)
		(property "Reference" "C131"
			(at 0 0 90)
			(layer "B.SilkS")
			(hide yes)
			(effects
				(font
					(size 1.27 1.27)
				)
				(justify mirror)
			)
		)
		(property "Value" ""
			(at 0 0 90)
			(layer "B.Fab")
			(effects
				(font
					(size 1.27 1.27)
				)
				(justify mirror)
			)
		)
		(duplicate_pad_numbers_are_jumpers no)
		(fp_line
			(start 0.299974 -0.150114)
			(end -0.299974 -0.150114)
			(stroke
				(width 0.1)
				(type default)
			)
			(layer "B.Fab")
		)
		(fp_line
			(start -0.299974 -0.150114)
			(end -0.299974 0.150114)
			(stroke
				(width 0.1)
				(type default)
			)
			(layer "B.Fab")
		)
		(fp_line
			(start 0.299974 0.150114)
			(end 0.299974 -0.150114)
			(stroke
				(width 0.1)
				(type default)
			)
			(layer "B.Fab")
		)
		(fp_line
			(start -0.299974 0.150114)
			(end 0.299974 0.150114)
			(stroke
				(width 0.1)
				(type default)
			)
			(layer "B.Fab")
		)
		(pad "1" smd rect
			(at 0.2667 0 270)
			(size 0.3048 0.381)
			(layers "B.Cu" "B.Mask" "B.Paste")
			(net "P1V8_CPU1_RT0_1A")
		)
		(pad "2" smd rect
			(at -0.2667 0 270)
			(size 0.3048 0.381)
			(layers "B.Cu" "B.Mask" "B.Paste")
			(net "GND")
		)
	)
	(footprint ""
		(layer "B.Cu")
		(at 54.718458 -388.011162 -90)
		(property "Reference" "C123"
			(at 0 0 90)
			(layer "B.SilkS")
			(hide yes)
			(effects
				(font
					(size 1.27 1.27)
				)
				(justify mirror)
			)
		)
		(property "Value" ""
			(at 0 0 90)
			(layer "B.Fab")
			(effects
				(font
					(size 1.27 1.27)
				)
				(justify mirror)
			)
		)
		(duplicate_pad_numbers_are_jumpers no)
		(fp_line
			(start -0.299974 0.150114)
			(end 0.299974 0.150114)
			(stroke
				(width 0.1)
				(type default)
			)
			(layer "B.Fab")
		)
		(fp_line
			(start 0.299974 0.150114)
			(end 0.299974 -0.150114)
			(stroke
				(width 0.1)
				(type default)
			)
			(layer "B.Fab")
		)
		(fp_line
			(start -0.299974 -0.150114)
			(end -0.299974 0.150114)
			(stroke
				(width 0.1)
				(type default)
			)
			(layer "B.Fab")
		)
		(fp_line
			(start 0.299974 -0.150114)
			(end -0.299974 -0.150114)
			(stroke
				(width 0.1)
				(type default)
			)
			(layer "B.Fab")
		)
		(pad "1" smd rect
			(at 0.2667 0 90)
			(size 0.3048 0.381)
			(layers "B.Cu" "B.Mask" "B.Paste")
			(net "P1V8_CPU1_RT0_1A")
		)
		(pad "2" smd rect
			(at -0.2667 0 90)
			(size 0.3048 0.381)
			(layers "B.Cu" "B.Mask" "B.Paste")
			(net "GND")
		)
	)
	(footprint ""
		(layer "B.Cu")
		(at 373.329454 -249.36831)
		(property "Reference" "C272"
			(at 0 0 0)
			(layer "B.SilkS")
			(hide yes)
			(effects
				(font
					(size 1.27 1.27)
				)
				(justify mirror)
			)
		)
		(property "Value" ""
			(at 0 0 0)
			(layer "B.Fab")
			(effects
				(font
					(size 1.27 1.27)
				)
				(justify mirror)
			)
		)
		(duplicate_pad_numbers_are_jumpers no)
		(fp_line
			(start -0.7874 -0.4064)
			(end -0.7874 0.4064)
			(stroke
				(width 0.1524)
				(type default)
			)
			(layer "B.SilkS")
		)
		(fp_line
			(start -0.7874 0.4064)
			(end 0.7874 0.4064)
			(stroke
				(width 0.1524)
				(type default)
			)
			(layer "B.SilkS")
		)
		(fp_line
			(start 0.7874 -0.4064)
			(end -0.7874 -0.4064)
			(stroke
				(width 0.1524)
				(type default)
			)
			(layer "B.SilkS")
		)
		(fp_line
			(start 0.7874 0.4064)
			(end 0.7874 -0.4064)
			(stroke
				(width 0.1524)
				(type default)
			)
			(layer "B.SilkS")
		)
		(fp_line
			(start -0.67945 -0.3048)
			(end -0.67945 0.3048)
			(stroke
				(width 0.1)
				(type default)
			)
			(layer "B.Fab")
		)
		(fp_line
			(start -0.67945 0.3048)
			(end -0.120396 0.3048)
			(stroke
				(width 0.1)
				(type default)
			)
			(layer "B.Fab")
		)
		(fp_line
			(start -0.12065 -0.3048)
			(end -0.67945 -0.3048)
			(stroke
				(width 0.1)
				(type default)
			)
			(layer "B.Fab")
		)
		(fp_line
			(start -0.12065 -0.2794)
			(end -0.12065 -0.3048)
			(stroke
				(width 0.1)
				(type default)
			)
			(layer "B.Fab")
		)
		(fp_line
			(start -0.120396 0.2794)
			(end 0.12065 0.2794)
			(stroke
				(width 0.1)
				(type default)
			)
			(layer "B.Fab")
		)
		(fp_line
			(start -0.120396 0.3048)
			(end -0.120396 0.2794)
			(stroke
				(width 0.1)
				(type default)
			)
			(layer "B.Fab")
		)
		(fp_line
			(start 0.12065 -0.305054)
			(end 0.12065 -0.2794)
			(stroke
				(width 0.1)
				(type default)
			)
			(layer "B.Fab")
		)
		(fp_line
			(start 0.12065 -0.2794)
			(end -0.12065 -0.2794)
			(stroke
				(width 0.1)
				(type default)
			)
			(layer "B.Fab")
		)
		(fp_line
			(start 0.12065 0.2794)
			(end 0.12065 0.3048)
			(stroke
				(width 0.1)
				(type default)
			)
			(layer "B.Fab")
		)
		(fp_line
			(start 0.12065 0.3048)
			(end 0.67945 0.3048)
			(stroke
				(width 0.1)
				(type default)
			)
			(layer "B.Fab")
		)
		(fp_line
			(start 0.67945 -0.305054)
			(end 0.12065 -0.305054)
			(stroke
				(width 0.1)
				(type default)
			)
			(layer "B.Fab")
		)
		(fp_line
			(start 0.67945 0.3048)
			(end 0.67945 -0.305054)
			(stroke
				(width 0.1)
				(type default)
			)
			(layer "B.Fab")
		)
		(pad "1" smd circle
			(at 0.40005 0 180)
			(size 0 0)
			(layers "B.Cu" "B.Mask" "B.Paste")
			(net "PVDDCR_CPU0_P0")
		)
		(pad "2" smd circle
			(at -0.40005 0 180)
			(size 0 0)
			(layers "B.Cu" "B.Mask" "B.Paste")
			(net "GND")
		)
	)
	(footprint ""
		(layer "B.Cu")
		(at 121.452386 -267.49883)
		(property "Reference" "C2381"
			(at 0 0 0)
			(layer "B.SilkS")
			(hide yes)
			(effects
				(font
					(size 1.27 1.27)
				)
				(justify mirror)
			)
		)
		(property "Value" ""
			(at 0 0 0)
			(layer "B.Fab")
			(effects
				(font
					(size 1.27 1.27)
				)
				(justify mirror)
			)
		)
		(duplicate_pad_numbers_are_jumpers no)
		(fp_line
			(start -0.7874 -0.4064)
			(end -0.7874 0.4064)
			(stroke
				(width 0.1524)
				(type default)
			)
			(layer "B.SilkS")
		)
		(fp_line
			(start -0.7874 0.4064)
			(end 0.7874 0.4064)
			(stroke
				(width 0.1524)
				(type default)
			)
			(layer "B.SilkS")
		)
		(fp_line
			(start 0.7874 -0.4064)
			(end -0.7874 -0.4064)
			(stroke
				(width 0.1524)
				(type default)
			)
			(layer "B.SilkS")
		)
		(fp_line
			(start 0.7874 0.4064)
			(end 0.7874 -0.4064)
			(stroke
				(width 0.1524)
				(type default)
			)
			(layer "B.SilkS")
		)
		(fp_line
			(start -0.67945 -0.3048)
			(end -0.67945 0.3048)
			(stroke
				(width 0.1)
				(type default)
			)
			(layer "B.Fab")
		)
		(fp_line
			(start -0.67945 0.3048)
			(end -0.120396 0.3048)
			(stroke
				(width 0.1)
				(type default)
			)
			(layer "B.Fab")
		)
		(fp_line
			(start -0.12065 -0.3048)
			(end -0.67945 -0.3048)
			(stroke
				(width 0.1)
				(type default)
			)
			(layer "B.Fab")
		)
		(fp_line
			(start -0.12065 -0.2794)
			(end -0.12065 -0.3048)
			(stroke
				(width 0.1)
				(type default)
			)
			(layer "B.Fab")
		)
		(fp_line
			(start -0.120396 0.2794)
			(end 0.12065 0.2794)
			(stroke
				(width 0.1)
				(type default)
			)
			(layer "B.Fab")
		)
		(fp_line
			(start -0.120396 0.3048)
			(end -0.120396 0.2794)
			(stroke
				(width 0.1)
				(type default)
			)
			(layer "B.Fab")
		)
		(fp_line
			(start 0.12065 -0.305054)
			(end 0.12065 -0.2794)
			(stroke
				(width 0.1)
				(type default)
			)
			(layer "B.Fab")
		)
		(fp_line
			(start 0.12065 -0.2794)
			(end -0.12065 -0.2794)
			(stroke
				(width 0.1)
				(type default)
			)
			(layer "B.Fab")
		)
		(fp_line
			(start 0.12065 0.2794)
			(end 0.12065 0.3048)
			(stroke
				(width 0.1)
				(type default)
			)
			(layer "B.Fab")
		)
		(fp_line
			(start 0.12065 0.3048)
			(end 0.67945 0.3048)
			(stroke
				(width 0.1)
				(type default)
			)
			(layer "B.Fab")
		)
		(fp_line
			(start 0.67945 -0.305054)
			(end 0.12065 -0.305054)
			(stroke
				(width 0.1)
				(type default)
			)
			(layer "B.Fab")
		)
		(fp_line
			(start 0.67945 0.3048)
			(end 0.67945 -0.305054)
			(stroke
				(width 0.1)
				(type default)
			)
			(layer "B.Fab")
		)
		(pad "1" smd circle
			(at 0.40005 0 180)
			(size 0 0)
			(layers "B.Cu" "B.Mask" "B.Paste")
			(net "PVDDCR_CPU1_P1")
		)
		(pad "2" smd circle
			(at -0.40005 0 180)
			(size 0 0)
			(layers "B.Cu" "B.Mask" "B.Paste")
			(net "GND")
		)
	)
	(footprint ""
		(layer "B.Cu")
		(at 388.630922 -416.899344 90)
		(property "Reference" "C6607"
			(at 0 0 90)
			(layer "B.SilkS")
			(hide yes)
			(effects
				(font
					(size 1.27 1.27)
				)
				(justify mirror)
			)
		)
		(property "Value" ""
			(at 0 0 90)
			(layer "B.Fab")
			(effects
				(font
					(size 1.27 1.27)
				)
				(justify mirror)
			)
		)
		(duplicate_pad_numbers_are_jumpers no)
		(fp_line
			(start 0.299974 -0.150114)
			(end -0.299974 -0.150114)
			(stroke
				(width 0.1)
				(type default)
			)
			(layer "B.Fab")
		)
		(fp_line
			(start -0.299974 -0.150114)
			(end -0.299974 0.150114)
			(stroke
				(width 0.1)
				(type default)
			)
			(layer "B.Fab")
		)
		(fp_line
			(start 0.299974 0.150114)
			(end 0.299974 -0.150114)
			(stroke
				(width 0.1)
				(type default)
			)
			(layer "B.Fab")
		)
		(fp_line
			(start -0.299974 0.150114)
			(end 0.299974 0.150114)
			(stroke
				(width 0.1)
				(type default)
			)
			(layer "B.Fab")
		)
		(pad "1" smd rect
			(at 0.2667 0 270)
			(size 0.3048 0.381)
			(layers "B.Cu" "B.Mask" "B.Paste")
			(net "P5E_CPU0_P3_TX_BUF_C_DP<5>")
		)
		(pad "2" smd rect
			(at -0.2667 0 270)
			(size 0.3048 0.381)
			(layers "B.Cu" "B.Mask" "B.Paste")
			(net "P5E_CPU0_P3_TX_BUF_DP<5>")
		)
	)
)
